(kicad_pcb
	(version 20260206)
	(generator "pcbnew")
	(generator_version "10.0")
	(general
		(thickness 1.21888)
		(legacy_teardrops no)
	)
	(paper "A4")
	(title_block
		(title "timecard-v8 — TimeCard-DC-V8_EXP.PcbDoc")
		(comment 1 "Time Appliance Project (Time Card) / footprints 187-194 of 288")
	)
	(layers
		(0 "F.Cu" signal "TOP")
		(4 "In1.Cu" signal "SGND")
		(6 "In2.Cu" signal "IN1")
		(8 "In3.Cu" signal "IN2")
		(10 "In4.Cu" signal "SGND1")
		(2 "B.Cu" signal "BOTTOM")
		(9 "F.Adhes" user "F.Adhesive")
		(11 "B.Adhes" user "B.Adhesive")
		(13 "F.Paste" user "Top Paste")
		(15 "B.Paste" user "Bottom Paste")
		(5 "F.SilkS" user "Top Overlay")
		(7 "B.SilkS" user "Bottom Overlay")
		(1 "F.Mask" user "Top Solder")
		(3 "B.Mask" user "Bottom Solder")
		(17 "Dwgs.User" user "User.Drawings")
		(19 "Cmts.User" user "User.Comments")
		(21 "Eco1.User" user "User.Eco1")
		(23 "Eco2.User" user "User.Eco2")
		(25 "Edge.Cuts" user)
		(27 "Margin" user)
		(31 "F.CrtYd" user "Top Courtyard")
		(29 "B.CrtYd" user "Bottom Courtyard")
		(35 "F.Fab" user "Top Component Center")
		(33 "B.Fab" user "Bottom Component Center")
	)
	(footprint "MIC24052YJL-TR:QFN28_5X6_MCH"
		(layer "F.Cu")
		(at 208.8261 124.2162 90)
		(property "Reference" "U18"
			(at 3.673079 1.1286 0)
			(unlocked yes)
			(layer "F.SilkS")
			(effects
				(font
					(size 0.762 0.762)
					(thickness 0.2286)
				)
			)
		)
		(property "Value" "MIC24052YJL-TR"
			(at 7.146775 5.297671 90)
			(unlocked yes)
			(layer "F.SilkS")
			(hide yes)
			(effects
				(font
					(size 0.762 0.762)
					(thickness 0.2286)
				)
			)
		)
		(sheetname "POWER")
		(sheetfile "POWER.kicad_sch")
		(duplicate_pad_numbers_are_jumpers no)
		(fp_line
			(start 2.9083 -3.4036)
			(end 2.9083 -2.56018)
			(stroke
				(width 0.1524)
				(type solid)
			)
			(layer "F.SilkS")
		)
		(fp_line
			(start 1.92049 -3.4036)
			(end 2.9083 -3.4036)
			(stroke
				(width 0.1524)
				(type solid)
			)
			(layer "F.SilkS")
		)
		(fp_line
			(start -2.9083 -3.4036)
			(end -1.92049 -3.4036)
			(stroke
				(width 0.1524)
				(type solid)
			)
			(layer "F.SilkS")
		)
		(fp_line
			(start -2.9083 -3.4036)
			(end -2.9083 -2.56018)
			(stroke
				(width 0.1524)
				(type solid)
			)
			(layer "F.SilkS")
		)
		(fp_line
			(start 2.9083 2.56018)
			(end 2.9083 3.4036)
			(stroke
				(width 0.1524)
				(type solid)
			)
			(layer "F.SilkS")
		)
		(fp_line
			(start -2.9083 2.56018)
			(end -2.9083 3.4036)
			(stroke
				(width 0.1524)
				(type solid)
			)
			(layer "F.SilkS")
		)
		(fp_line
			(start 1.92049 3.4036)
			(end 2.9083 3.4036)
			(stroke
				(width 0.1524)
				(type solid)
			)
			(layer "F.SilkS")
		)
		(fp_line
			(start -2.9083 3.4036)
			(end -1.92049 3.4036)
			(stroke
				(width 0.1524)
				(type solid)
			)
			(layer "F.SilkS")
		)
		(fp_text user "*"
			(at -3.5557 -2.190425 90)
			(unlocked yes)
			(layer "F.SilkS")
			(effects
				(font
					(size 1.27 1.27)
					(thickness 0.0762)
				)
				(justify left bottom)
			)
		)
		(pad "1" smd rect
			(at -2.4 -2.275)
			(size 0.3 0.4)
			(layers "F.Cu" "F.Mask" "F.Paste")
			(net "P3V3_PVDD")
			(solder_mask_margin 0)
			(solder_paste_margin -0.15)
		)
		(pad "2" smd rect
			(at -2.4 -1.625)
			(size 0.3 0.4)
			(layers "F.Cu" "F.Mask" "F.Paste")
			(net "GND")
			(solder_mask_margin 0)
			(solder_paste_margin -0.15)
		)
		(pad "3" smd rect
			(at -2.4 -0.975)
			(size 0.3 0.4)
			(layers "F.Cu" "F.Mask" "F.Paste")
			(solder_mask_margin 0)
			(solder_paste_margin -0.15)
		)
		(pad "4" smd rect
			(at -2.4 -0.325)
			(size 0.3 0.4)
			(layers "F.Cu" "F.Mask" "F.Paste")
			(net "NetL2_1")
			(solder_mask_margin 0)
			(solder_paste_margin -0.15)
		)
		(pad "5" smd rect
			(at -2.4 0.325)
			(size 0.3 0.4)
			(layers "F.Cu" "F.Mask" "F.Paste")
			(net "GND")
			(solder_mask_margin 0)
			(solder_paste_margin -0.15)
		)
		(pad "6" smd rect
			(at -2.4 0.975)
			(size 0.3 0.4)
			(layers "F.Cu" "F.Mask" "F.Paste")
			(net "GND")
			(solder_mask_margin 0)
			(solder_paste_margin -0.15)
		)
		(pad "7" smd rect
			(at -2.4 1.625)
			(size 0.3 0.4)
			(layers "F.Cu" "F.Mask" "F.Paste")
			(net "GND")
			(solder_mask_margin 0)
			(solder_paste_margin -0.15)
		)
		(pad "8" smd rect
			(at -2.4 2.275)
			(size 0.3 0.4)
			(layers "F.Cu" "F.Mask" "F.Paste")
			(net "GND")
			(solder_mask_margin 0)
			(solder_paste_margin -0.15)
		)
		(pad "9" smd rect
			(at -1.625 2.9 270)
			(size 0.3 0.4)
			(layers "F.Cu" "F.Mask" "F.Paste")
			(net "NetL2_1")
			(solder_mask_margin 0)
			(solder_paste_margin -0.15)
		)
		(pad "10" smd rect
			(at -0.975 2.9 270)
			(size 0.3 0.4)
			(layers "F.Cu" "F.Mask" "F.Paste")
			(net "NetL2_1")
			(solder_mask_margin 0)
			(solder_paste_margin -0.15)
		)
		(pad "11" smd rect
			(at -0.325 2.9 270)
			(size 0.3 0.4)
			(layers "F.Cu" "F.Mask" "F.Paste")
			(net "NetL2_1")
			(solder_mask_margin 0)
			(solder_paste_margin -0.15)
		)
		(pad "12" smd rect
			(at 0.325 2.9 270)
			(size 0.3 0.4)
			(layers "F.Cu" "F.Mask" "F.Paste")
			(net "NetL2_1")
			(solder_mask_margin 0)
			(solder_paste_margin -0.15)
		)
		(pad "13" smd rect
			(at 0.975 2.9 270)
			(size 0.3 0.4)
			(layers "F.Cu" "F.Mask" "F.Paste")
			(net "+12V")
			(solder_mask_margin 0)
			(solder_paste_margin -0.15)
		)
		(pad "14" smd rect
			(at 1.625 2.9 270)
			(size 0.3 0.4)
			(layers "F.Cu" "F.Mask" "F.Paste")
			(net "+12V")
			(solder_mask_margin 0)
			(solder_paste_margin -0.15)
		)
		(pad "15" smd rect
			(at 2.4 2.275)
			(size 0.3 0.4)
			(layers "F.Cu" "F.Mask" "F.Paste")
			(net "+12V")
			(solder_mask_margin 0)
			(solder_paste_margin -0.15)
		)
		(pad "16" smd rect
			(at 2.4 1.625)
			(size 0.3 0.4)
			(layers "F.Cu" "F.Mask" "F.Paste")
			(net "+12V")
			(solder_mask_margin 0)
			(solder_paste_margin -0.15)
		)
		(pad "17" smd rect
			(at 2.4 0.975)
			(size 0.3 0.4)
			(layers "F.Cu" "F.Mask" "F.Paste")
			(net "+12V")
			(solder_mask_margin 0)
			(solder_paste_margin -0.15)
		)
		(pad "18" smd rect
			(at 2.4 0.325)
			(size 0.3 0.4)
			(layers "F.Cu" "F.Mask" "F.Paste")
			(net "+12V")
			(solder_mask_margin 0)
			(solder_paste_margin -0.15)
		)
		(pad "19" smd rect
			(at 2.4 -0.325)
			(size 0.3 0.4)
			(layers "F.Cu" "F.Mask" "F.Paste")
			(net "+12V")
			(solder_mask_margin 0)
			(solder_paste_margin -0.15)
		)
		(pad "20" smd rect
			(at 2.4 -0.975)
			(size 0.3 0.4)
			(layers "F.Cu" "F.Mask" "F.Paste")
			(net "NetR69_1")
			(solder_mask_margin 0)
			(solder_paste_margin -0.15)
		)
		(pad "21" smd rect
			(at 2.4 -1.625)
			(size 0.3 0.4)
			(layers "F.Cu" "F.Mask" "F.Paste")
			(net "GND")
			(solder_mask_margin 0)
			(solder_paste_margin -0.15)
		)
		(pad "22" smd rect
			(at 2.4 -2.275)
			(size 0.3 0.4)
			(layers "F.Cu" "F.Mask" "F.Paste")
			(net "NetC68_2")
			(solder_mask_margin 0)
			(solder_paste_margin -0.15)
		)
		(pad "23" smd rect
			(at 1.625 -2.9 270)
			(size 0.3 0.4)
			(layers "F.Cu" "F.Mask" "F.Paste")
			(net "GND")
			(solder_mask_margin 0)
			(solder_paste_margin -0.15)
		)
		(pad "24" smd rect
			(at 0.975 -2.9 270)
			(size 0.3 0.4)
			(layers "F.Cu" "F.Mask" "F.Paste")
			(net "P3V3_FB")
			(solder_mask_margin 0)
			(solder_paste_margin -0.15)
		)
		(pad "25" smd rect
			(at 0.325 -2.9 270)
			(size 0.3 0.4)
			(layers "F.Cu" "F.Mask" "F.Paste")
			(net "NetR68_2")
			(solder_mask_margin 0)
			(solder_paste_margin -0.15)
		)
		(pad "26" smd rect
			(at -0.325 -2.9 270)
			(size 0.3 0.4)
			(layers "F.Cu" "F.Mask" "F.Paste")
			(net "NetR67_2")
			(solder_mask_margin 0)
			(solder_paste_margin -0.15)
		)
		(pad "27" smd rect
			(at -0.975 -2.9 270)
			(size 0.3 0.4)
			(layers "F.Cu" "F.Mask" "F.Paste")
			(net "NetC71_1")
			(solder_mask_margin 0)
			(solder_paste_margin -0.15)
		)
		(pad "28" smd rect
			(at -1.625 -2.9 270)
			(size 0.3 0.4)
			(layers "F.Cu" "F.Mask" "F.Paste")
			(net "P3V3_VDD")
			(solder_mask_margin 0)
			(solder_paste_margin -0.15)
		)
		(pad "29" smd rect
			(at 0 -1.55 90)
			(size 3.69999 1.6)
			(layers "F.Cu" "F.Mask" "F.Paste")
			(net "GND")
			(solder_mask_margin 0)
			(solder_paste_margin -0.8)
		)
		(pad "30" smd rect
			(at -0.5 1.015 90)
			(size 2.2 2.82999)
			(layers "F.Cu" "F.Mask" "F.Paste")
			(net "NetL2_1")
			(solder_mask_margin 0)
			(solder_paste_margin 0)
		)
		(pad "31" smd rect
			(at 1.4 1.015 90)
			(size 0.9 2.82999)
			(layers "F.Cu" "F.Mask" "F.Paste")
		)
	)
	(footprint "Vault:FP-SML-LX0603IW-TR-MFG"
		(layer "F.Cu")
		(at 174.0261 88.0162 -90)
		(property "Reference" "D24"
			(at 0.4286 -1.573069 270)
			(unlocked yes)
			(layer "F.SilkS")
			(effects
				(font
					(size 0.762 0.762)
					(thickness 0.2286)
				)
			)
		)
		(property "Value" "SML-LX0603IW-TR"
			(at -3.519671 10.677135 180)
			(unlocked yes)
			(layer "F.SilkS")
			(hide yes)
			(effects
				(font
					(size 0.762 0.762)
					(thickness 0.2286)
				)
			)
		)
		(sheetname "USBUart_DipSelects")
		(sheetfile "USBUart_DipSelects.kicad_sch")
		(duplicate_pad_numbers_are_jumpers no)
		(fp_line
			(start 0.77933 0.73)
			(end -0.82067 0.73)
			(stroke
				(width 0.2)
				(type solid)
			)
			(layer "F.SilkS")
		)
		(fp_line
			(start 0.8 -0.75)
			(end -0.8 -0.75)
			(stroke
				(width 0.2)
				(type solid)
			)
			(layer "F.SilkS")
		)
		(fp_circle
			(center -1.725 0)
			(end -1.85 0)
			(stroke
				(width 0.25)
				(type solid)
			)
			(fill no)
			(layer "F.SilkS")
		)
		(fp_line
			(start -1.25 0.625)
			(end -1.25 -0.625)
			(stroke
				(width 0.2)
				(type solid)
			)
			(layer "F.CrtYd")
		)
		(fp_line
			(start 1.25 0.625)
			(end -1.25 0.625)
			(stroke
				(width 0.2)
				(type solid)
			)
			(layer "F.CrtYd")
		)
		(fp_line
			(start 1.25 0.625)
			(end 1.25 -0.625)
			(stroke
				(width 0.2)
				(type solid)
			)
			(layer "F.CrtYd")
		)
		(fp_line
			(start 1.25 -0.625)
			(end -1.25 -0.625)
			(stroke
				(width 0.2)
				(type solid)
			)
			(layer "F.CrtYd")
		)
		(fp_line
			(start -1.25 0.625)
			(end -1.25 -0.625)
			(stroke
				(width 0.2)
				(type solid)
			)
			(layer "F.Fab")
		)
		(fp_line
			(start 1.25 0.625)
			(end -1.25 0.625)
			(stroke
				(width 0.2)
				(type solid)
			)
			(layer "F.Fab")
		)
		(fp_line
			(start 1.25 0.625)
			(end 1.25 -0.625)
			(stroke
				(width 0.2)
				(type solid)
			)
			(layer "F.Fab")
		)
		(fp_line
			(start 0 0.5)
			(end 0 -0.5)
			(stroke
				(width 0.1)
				(type solid)
			)
			(layer "F.Fab")
		)
		(fp_line
			(start 0.5 0)
			(end -0.5 0)
			(stroke
				(width 0.1)
				(type solid)
			)
			(layer "F.Fab")
		)
		(fp_line
			(start 1.25 -0.625)
			(end -1.25 -0.625)
			(stroke
				(width 0.2)
				(type solid)
			)
			(layer "F.Fab")
		)
		(fp_text user "${REFERENCE}"
			(at 0 0.29535 270)
			(unlocked yes)
			(layer "F.Fab")
			(effects
				(font
					(face "Arial")
					(size 0.63 0.63)
					(thickness 0.1)
				)
				(justify left bottom)
			)
		)
		(pad "1" smd rect
			(at -0.75 0 270)
			(size 0.8 0.8)
			(layers "F.Cu" "F.Mask" "F.Paste")
			(net "NetD24_1")
			(solder_mask_margin 0)
			(solder_paste_margin 0)
		)
		(pad "2" smd rect
			(at 0.75 0 270)
			(size 0.8 0.8)
			(layers "F.Cu" "F.Mask" "F.Paste")
			(net "+3.3V")
			(solder_mask_margin 0)
			(solder_paste_margin 0)
		)
	)
	(footprint "Vault:RESC1005X40X25NL05T05"
		(layer "F.Cu")
		(at 208.9261 77.5162)
		(property "Reference" "R91"
			(at -0.371395 -1.173069 0)
			(unlocked yes)
			(layer "F.SilkS")
			(effects
				(font
					(size 0.762 0.762)
					(thickness 0.2286)
				)
			)
		)
		(property "Value" "27_1%_0402"
			(at -2.732271 7.37632 270)
			(unlocked yes)
			(layer "F.SilkS")
			(hide yes)
			(effects
				(font
					(size 0.762 0.762)
					(thickness 0.2286)
				)
			)
		)
		(sheetname "USBUart_DipSelects")
		(sheetfile "USBUart_DipSelects.kicad_sch")
		(duplicate_pad_numbers_are_jumpers no)
		(pad "1" smd rect
			(at -0.45 0 90)
			(size 0.55 0.55)
			(layers "F.Cu" "F.Mask" "F.Paste")
			(net "GPS2_TX_FPGA")
		)
		(pad "2" smd rect
			(at 0.45 0 90)
			(size 0.55 0.55)
			(layers "F.Cu" "F.Mask" "F.Paste")
			(net "NetR91_2")
		)
	)
	(footprint "SA53:SolderSocket"
		(layer "F.Cu")
		(at 99.3261 135.5162 90)
		(property "Reference" "SKT5"
			(at -6.626931 0.3286 0)
			(unlocked yes)
			(layer "F.SilkS")
			(effects
				(font
					(size 0.762 0.762)
					(thickness 0.2286)
				)
			)
		)
		(property "Value" "0332-0-43-80-18-27-10-0"
			(at -2.910071 16.1362 0)
			(unlocked yes)
			(layer "F.SilkS")
			(hide yes)
			(effects
				(font
					(size 0.762 0.762)
					(thickness 0.2286)
				)
			)
		)
		(sheetname "MAC")
		(sheetfile "MAC.kicad_sch")
		(duplicate_pad_numbers_are_jumpers no)
		(pad "1" thru_hole circle
			(at 0 0 90)
			(size 2.54 2.54)
			(drill 2.0066)
			(layers "*.Cu" "*.Mask")
			(remove_unused_layers no)
			(net "MAC_RF_OUT")
			(thermal_bridge_angle 90)
		)
	)
	(footprint "Vault:CAPC1005X56X25NL10T15"
		(layer "F.Cu")
		(at 226.6261 112.4162 90)
		(property "Reference" "C21"
			(at -1.3 -0.493345 270)
			(unlocked yes)
			(layer "F.SilkS")
			(effects
				(font
					(size 0.762 0.762)
					(thickness 0.2286)
				)
				(justify left bottom)
			)
		)
		(property "Value" "0.1uF_0402"
			(at 5.060155 26.4395 0)
			(unlocked yes)
			(layer "F.SilkS")
			(hide yes)
			(effects
				(font
					(size 0.762 0.762)
					(thickness 0.2286)
				)
				(justify left bottom)
			)
		)
		(sheetname "POWER")
		(sheetfile "POWER.kicad_sch")
		(duplicate_pad_numbers_are_jumpers no)
		(pad "1" smd rect
			(at -0.44 0 180)
			(size 0.64 0.68)
			(layers "F.Cu" "F.Mask" "F.Paste")
			(net "GND")
		)
		(pad "2" smd rect
			(at 0.44 0 180)
			(size 0.64 0.68)
			(layers "F.Cu" "F.Mask" "F.Paste")
			(net "+3.3V")
		)
	)
	(footprint "Vault:FP-STPS5L60S-MFG"
		(layer "F.Cu")
		(at 214.5261 89.2162 90)
		(property "Reference" "D12"
			(at -0.3286 3.973069 270)
			(unlocked yes)
			(layer "F.SilkS")
			(effects
				(font
					(size 0.762 0.762)
					(thickness 0.2286)
				)
			)
		)
		(property "Value" "STPS5L60S"
			(at -6.491471 3.76976 0)
			(unlocked yes)
			(layer "F.SilkS")
			(hide yes)
			(effects
				(font
					(size 0.762 0.762)
					(thickness 0.2286)
				)
			)
		)
		(sheetname "POWER")
		(sheetfile "POWER.kicad_sch")
		(duplicate_pad_numbers_are_jumpers no)
		(fp_line
			(start 3.575 -3.125)
			(end 3.575 -2.025)
			(stroke
				(width 0.2)
				(type solid)
			)
			(layer "F.SilkS")
		)
		(fp_line
			(start -3.575 -3.125)
			(end 3.575 -3.125)
			(stroke
				(width 0.2)
				(type solid)
			)
			(layer "F.SilkS")
		)
		(fp_line
			(start -3.575 -3.125)
			(end -3.575 -2.025)
			(stroke
				(width 0.2)
				(type solid)
			)
			(layer "F.SilkS")
		)
		(fp_line
			(start 3.575 2.025)
			(end 3.575 3.125)
			(stroke
				(width 0.2)
				(type solid)
			)
			(layer "F.SilkS")
		)
		(fp_line
			(start -3.575 2.025)
			(end -3.575 3.125)
			(stroke
				(width 0.2)
				(type solid)
			)
			(layer "F.SilkS")
		)
		(fp_line
			(start -3.575 3.125)
			(end 3.575 3.125)
			(stroke
				(width 0.2)
				(type solid)
			)
			(layer "F.SilkS")
		)
		(fp_circle
			(center -4.7 -0.025)
			(end -4.575 -0.025)
			(stroke
				(width 0.25)
				(type solid)
			)
			(fill no)
			(layer "F.SilkS")
		)
		(fp_line
			(start 4.195 -3.225)
			(end 4.195 3.225)
			(stroke
				(width 0.2)
				(type solid)
			)
			(layer "F.CrtYd")
		)
		(fp_line
			(start -4.195 -3.225)
			(end 4.195 -3.225)
			(stroke
				(width 0.2)
				(type solid)
			)
			(layer "F.CrtYd")
		)
		(fp_line
			(start -4.195 -3.225)
			(end -4.195 3.225)
			(stroke
				(width 0.2)
				(type solid)
			)
			(layer "F.CrtYd")
		)
		(fp_line
			(start -4.195 3.225)
			(end 4.195 3.225)
			(stroke
				(width 0.2)
				(type solid)
			)
			(layer "F.CrtYd")
		)
		(fp_line
			(start 4.195 -3.225)
			(end 4.195 3.225)
			(stroke
				(width 0.2)
				(type solid)
			)
			(layer "F.Fab")
		)
		(fp_line
			(start -4.195 -3.225)
			(end 4.195 -3.225)
			(stroke
				(width 0.2)
				(type solid)
			)
			(layer "F.Fab")
		)
		(fp_line
			(start -4.195 -3.225)
			(end -4.195 3.225)
			(stroke
				(width 0.2)
				(type solid)
			)
			(layer "F.Fab")
		)
		(fp_line
			(start 0 -0.5)
			(end 0 0.5)
			(stroke
				(width 0.1)
				(type solid)
			)
			(layer "F.Fab")
		)
		(fp_line
			(start -0.5 0)
			(end 0.5 0)
			(stroke
				(width 0.1)
				(type solid)
			)
			(layer "F.Fab")
		)
		(fp_line
			(start -4.195 3.225)
			(end 4.195 3.225)
			(stroke
				(width 0.2)
				(type solid)
			)
			(layer "F.Fab")
		)
		(fp_text user "${REFERENCE}"
			(at -0.00002 0.10711 90)
			(unlocked yes)
			(layer "F.Fab")
			(effects
				(font
					(face "Arial")
					(size 0.63 0.63)
					(thickness 0.1)
				)
				(justify left bottom)
			)
		)
		(pad "1" smd rect
			(at -3.325 0 90)
			(size 1.54 3.14)
			(layers "F.Cu" "F.Mask" "F.Paste")
			(net "NetD12_1")
			(solder_mask_margin 0)
			(solder_paste_margin 0)
		)
		(pad "2" smd rect
			(at 3.325 0 90)
			(size 1.54 3.14)
			(layers "F.Cu" "F.Mask" "F.Paste")
			(net "NetD12_2")
			(solder_mask_margin 0)
			(solder_paste_margin 0)
		)
	)
	(footprint "Vault:RESC1608X55X30NL15T15"
		(layer "F.Cu")
		(at 82.3761 125.8662 -90)
		(property "Reference" "R17"
			(at 2.7714 -0.026921 90)
			(unlocked yes)
			(layer "F.SilkS")
			(effects
				(font
					(size 0.762 0.762)
					(thickness 0.2286)
				)
			)
		)
		(property "Value" "4.7K"
			(at -2.884671 3.18659 180)
			(unlocked yes)
			(layer "F.SilkS")
			(hide yes)
			(effects
				(font
					(size 0.762 0.762)
					(thickness 0.2286)
				)
			)
		)
		(sheetname "USER_IO")
		(sheetfile "USER_IO.kicad_sch")
		(duplicate_pad_numbers_are_jumpers no)
		(pad "1" smd rect
			(at -0.75 0)
			(size 0.95 0.95)
			(layers "F.Cu" "F.Mask" "F.Paste")
			(net "ANT3_IO_IN")
		)
		(pad "2" smd rect
			(at 0.75 0)
			(size 0.95 0.95)
			(layers "F.Cu" "F.Mask" "F.Paste")
			(net "+3.3V")
		)
	)
	(footprint "SA53:SolderSocket"
		(layer "F.Cu")
		(at 137.8261 138.2162 90)
		(property "Reference" "SKT4"
			(at -3.426921 3.0286 0)
			(unlocked yes)
			(layer "F.SilkS")
			(effects
				(font
					(size 0.762 0.762)
					(thickness 0.2286)
				)
			)
		)
		(property "Value" "0332-0-43-80-18-27-10-0"
			(at -2.910071 16.1362 0)
			(unlocked yes)
			(layer "F.SilkS")
			(hide yes)
			(effects
				(font
					(size 0.762 0.762)
					(thickness 0.2286)
				)
			)
		)
		(sheetname "MAC")
		(sheetfile "MAC.kicad_sch")
		(duplicate_pad_numbers_are_jumpers no)
		(pad "1" thru_hole circle
			(at 0 0 90)
			(size 2.54 2.54)
			(drill 2.0066)
			(layers "*.Cu" "*.Mask")
			(remove_unused_layers no)
			(net "MAC_BITE")
			(thermal_bridge_angle 90)
		)
	)
)
